(kicad_pcb
	(version 20260206)
	(generator "pcbnew")
	(generator_version "10.0")
	(general
		(thickness 1.6)
		(legacy_teardrops no)
	)
	(paper "A4")
	(title_block
		(title "12092022_DA0F0TMDCD0_F0T_Management_Board_D_brd_V3_OCP.brd")
		(comment 1 "Grand Teton / footprints 684-689 of 1440")
	)
	(layers
		(0 "F.Cu" signal "TOP")
		(4 "In1.Cu" signal "GND")
		(6 "In2.Cu" signal "IN1")
		(8 "In3.Cu" signal "GND1")
		(10 "In4.Cu" signal "IN2")
		(12 "In5.Cu" signal "VCC")
		(14 "In6.Cu" signal "VCC1")
		(16 "In7.Cu" signal "IN3")
		(18 "In8.Cu" signal "GND2")
		(20 "In9.Cu" signal "IN4")
		(22 "In10.Cu" signal "GND3")
		(2 "B.Cu" signal "BOTTOM")
		(9 "F.Adhes" user "F.Adhesive")
		(11 "B.Adhes" user "B.Adhesive")
		(13 "F.Paste" user "Package Geometry/Pastemask Top")
		(15 "B.Paste" user "Package Geometry/Pastemask Bottom")
		(5 "F.SilkS" user "Ref Des/Silkscreen Top")
		(7 "B.SilkS" user "Ref Des/Silkscreen Bottom")
		(1 "F.Mask" user "Board Geometry/Soldermask Top")
		(3 "B.Mask" user "Board Geometry/Soldermask Bottom")
		(17 "Dwgs.User" user "User.Drawings")
		(19 "Cmts.User" user "User.Comments")
		(21 "Eco1.User" user "User.Eco1")
		(23 "Eco2.User" user "User.Eco2")
		(25 "Edge.Cuts" user "Board Geometry/Outline")
		(27 "Margin" user)
		(31 "F.CrtYd" user "Package Geometry/Place Bound Top")
		(29 "B.CrtYd" user "Package Geometry/Place Bound Bottom")
		(35 "F.Fab" user "Ref Des/Assembly Top")
		(33 "B.Fab" user "Ref Des/Assembly Bottom")
	)
	(footprint ""
		(layer "F.Cu")
		(at 25.4 -24.003 90)
		(property "Reference" "PC266"
			(at 0 0 90)
			(layer "F.SilkS")
			(hide yes)
			(effects
				(font
					(size 1.27 1.27)
				)
			)
		)
		(property "Value" ""
			(at 0 0 90)
			(layer "F.Fab")
			(effects
				(font
					(size 1.27 1.27)
				)
			)
		)
		(duplicate_pad_numbers_are_jumpers no)
		(fp_line
			(start 0.7874 -0.4064)
			(end 0.7874 0.4064)
			(stroke
				(width 0.1524)
				(type default)
			)
			(layer "F.SilkS")
		)
		(fp_line
			(start -0.7874 -0.4064)
			(end 0.7874 -0.4064)
			(stroke
				(width 0.1524)
				(type default)
			)
			(layer "F.SilkS")
		)
		(fp_line
			(start 0.7874 0.4064)
			(end -0.7874 0.4064)
			(stroke
				(width 0.1524)
				(type default)
			)
			(layer "F.SilkS")
		)
		(fp_line
			(start -0.7874 0.4064)
			(end -0.7874 -0.4064)
			(stroke
				(width 0.1524)
				(type default)
			)
			(layer "F.SilkS")
		)
		(fp_line
			(start -0.12065 -0.305054)
			(end -0.12065 -0.2794)
			(stroke
				(width 0.1)
				(type default)
			)
			(layer "F.Fab")
		)
		(fp_line
			(start -0.67945 -0.305054)
			(end -0.12065 -0.305054)
			(stroke
				(width 0.1)
				(type default)
			)
			(layer "F.Fab")
		)
		(fp_line
			(start 0.67945 -0.3048)
			(end 0.67945 0.3048)
			(stroke
				(width 0.1)
				(type default)
			)
			(layer "F.Fab")
		)
		(fp_line
			(start 0.12065 -0.3048)
			(end 0.67945 -0.3048)
			(stroke
				(width 0.1)
				(type default)
			)
			(layer "F.Fab")
		)
		(fp_line
			(start 0.12065 -0.2794)
			(end 0.12065 -0.3048)
			(stroke
				(width 0.1)
				(type default)
			)
			(layer "F.Fab")
		)
		(fp_line
			(start -0.12065 -0.2794)
			(end 0.12065 -0.2794)
			(stroke
				(width 0.1)
				(type default)
			)
			(layer "F.Fab")
		)
		(fp_line
			(start 0.120396 0.2794)
			(end -0.12065 0.2794)
			(stroke
				(width 0.1)
				(type default)
			)
			(layer "F.Fab")
		)
		(fp_line
			(start -0.12065 0.2794)
			(end -0.12065 0.3048)
			(stroke
				(width 0.1)
				(type default)
			)
			(layer "F.Fab")
		)
		(fp_line
			(start 0.67945 0.3048)
			(end 0.120396 0.3048)
			(stroke
				(width 0.1)
				(type default)
			)
			(layer "F.Fab")
		)
		(fp_line
			(start 0.120396 0.3048)
			(end 0.120396 0.2794)
			(stroke
				(width 0.1)
				(type default)
			)
			(layer "F.Fab")
		)
		(fp_line
			(start -0.12065 0.3048)
			(end -0.67945 0.3048)
			(stroke
				(width 0.1)
				(type default)
			)
			(layer "F.Fab")
		)
		(fp_line
			(start -0.67945 0.3048)
			(end -0.67945 -0.305054)
			(stroke
				(width 0.1)
				(type default)
			)
			(layer "F.Fab")
		)
		(pad "1" smd circle
			(at -0.40005 0 90)
			(size 0 0)
			(layers "F.Cu" "F.Mask" "F.Paste")
			(net "P1V0_AUX")
		)
		(pad "2" smd circle
			(at 0.40005 0 90)
			(size 0 0)
			(layers "F.Cu" "F.Mask" "F.Paste")
			(net "GND")
		)
	)
	(footprint ""
		(layer "F.Cu")
		(at 78.9432 -10.668)
		(property "Reference" ""
			(at 0 0 0)
			(layer "F.SilkS")
			(hide yes)
			(effects
				(font
					(size 1.27 1.27)
				)
			)
		)
		(property "Value" ""
			(at 0 0 0)
			(layer "F.Fab")
			(effects
				(font
					(size 1.27 1.27)
				)
			)
		)
		(duplicate_pad_numbers_are_jumpers no)
		(pad "1" smd circle
			(at 0 0)
			(size 0.9906 0.9906)
			(layers "F.Cu" "F.Mask" "F.Paste")
			(net "Net_325")
		)
		(zone
			(layer "F.Cu")
			(hatch none 0.5)
			(connect_pads
				(clearance 0)
			)
			(min_thickness 0.25)
			(keepout
				(tracks not_allowed)
				(vias allowed)
				(pads allowed)
				(copperpour not_allowed)
				(footprints allowed)
			)
			(placement
				(enabled no)
				(sheetname "")
			)
			(fill
				(thermal_gap 0.5)
				(thermal_bridge_width 0.5)
				(island_removal_mode 0)
			)
			(polygon
				(pts
					(arc
						(start 80.5688 -10.668)
						(mid 77.3176 -10.668)
						(end 80.5688 -10.668)
					)
				)
			)
		)
	)
	(footprint ""
		(layer "F.Cu")
		(at 38.354 -36.068 180)
		(property "Reference" "R232"
			(at 0 0 180)
			(layer "F.SilkS")
			(hide yes)
			(effects
				(font
					(size 1.27 1.27)
				)
			)
		)
		(property "Value" ""
			(at 0 0 180)
			(layer "F.Fab")
			(effects
				(font
					(size 1.27 1.27)
				)
			)
		)
		(duplicate_pad_numbers_are_jumpers no)
		(fp_line
			(start 0.7874 0.4064)
			(end -0.7874 0.4064)
			(stroke
				(width 0.1524)
				(type default)
			)
			(layer "F.SilkS")
		)
		(fp_line
			(start 0.7874 -0.4064)
			(end 0.7874 0.4064)
			(stroke
				(width 0.1524)
				(type default)
			)
			(layer "F.SilkS")
		)
		(fp_line
			(start -0.7874 0.4064)
			(end -0.7874 -0.4064)
			(stroke
				(width 0.1524)
				(type default)
			)
			(layer "F.SilkS")
		)
		(fp_line
			(start -0.7874 -0.4064)
			(end 0.7874 -0.4064)
			(stroke
				(width 0.1524)
				(type default)
			)
			(layer "F.SilkS")
		)
		(fp_line
			(start 0.67945 0.3048)
			(end 0.120396 0.3048)
			(stroke
				(width 0.1)
				(type default)
			)
			(layer "F.Fab")
		)
		(fp_line
			(start 0.67945 -0.3048)
			(end 0.67945 0.3048)
			(stroke
				(width 0.1)
				(type default)
			)
			(layer "F.Fab")
		)
		(fp_line
			(start 0.12065 -0.2794)
			(end 0.12065 -0.3048)
			(stroke
				(width 0.1)
				(type default)
			)
			(layer "F.Fab")
		)
		(fp_line
			(start 0.12065 -0.3048)
			(end 0.67945 -0.3048)
			(stroke
				(width 0.1)
				(type default)
			)
			(layer "F.Fab")
		)
		(fp_line
			(start 0.120396 0.3048)
			(end 0.120396 0.2794)
			(stroke
				(width 0.1)
				(type default)
			)
			(layer "F.Fab")
		)
		(fp_line
			(start 0.120396 0.2794)
			(end -0.12065 0.2794)
			(stroke
				(width 0.1)
				(type default)
			)
			(layer "F.Fab")
		)
		(fp_line
			(start -0.12065 0.3048)
			(end -0.67945 0.3048)
			(stroke
				(width 0.1)
				(type default)
			)
			(layer "F.Fab")
		)
		(fp_line
			(start -0.12065 0.2794)
			(end -0.12065 0.3048)
			(stroke
				(width 0.1)
				(type default)
			)
			(layer "F.Fab")
		)
		(fp_line
			(start -0.12065 -0.2794)
			(end 0.12065 -0.2794)
			(stroke
				(width 0.1)
				(type default)
			)
			(layer "F.Fab")
		)
		(fp_line
			(start -0.12065 -0.305054)
			(end -0.12065 -0.2794)
			(stroke
				(width 0.1)
				(type default)
			)
			(layer "F.Fab")
		)
		(fp_line
			(start -0.67945 0.3048)
			(end -0.67945 -0.305054)
			(stroke
				(width 0.1)
				(type default)
			)
			(layer "F.Fab")
		)
		(fp_line
			(start -0.67945 -0.305054)
			(end -0.12065 -0.305054)
			(stroke
				(width 0.1)
				(type default)
			)
			(layer "F.Fab")
		)
		(pad "1" smd circle
			(at -0.40005 0 180)
			(size 0 0)
			(layers "F.Cu" "F.Mask" "F.Paste")
			(net "P1V8_AUX")
		)
		(pad "2" smd circle
			(at 0.40005 0 180)
			(size 0 0)
			(layers "F.Cu" "F.Mask" "F.Paste")
			(net "P3V3_P1V8_I2C_I3C")
		)
	)
	(footprint ""
		(layer "F.Cu")
		(at 56.204612 -34.637726 -90)
		(property "Reference" "R19"
			(at 0 0 270)
			(layer "F.SilkS")
			(hide yes)
			(effects
				(font
					(size 1.27 1.27)
				)
			)
		)
		(property "Value" ""
			(at 0 0 270)
			(layer "F.Fab")
			(effects
				(font
					(size 1.27 1.27)
				)
			)
		)
		(duplicate_pad_numbers_are_jumpers no)
		(fp_line
			(start -0.7874 0.4064)
			(end -0.7874 -0.4064)
			(stroke
				(width 0.1524)
				(type default)
			)
			(layer "F.SilkS")
		)
		(fp_line
			(start 0.7874 0.4064)
			(end -0.7874 0.4064)
			(stroke
				(width 0.1524)
				(type default)
			)
			(layer "F.SilkS")
		)
		(fp_line
			(start -0.7874 -0.4064)
			(end 0.7874 -0.4064)
			(stroke
				(width 0.1524)
				(type default)
			)
			(layer "F.SilkS")
		)
		(fp_line
			(start 0.7874 -0.4064)
			(end 0.7874 0.4064)
			(stroke
				(width 0.1524)
				(type default)
			)
			(layer "F.SilkS")
		)
		(fp_line
			(start -0.67945 0.3048)
			(end -0.67945 -0.305054)
			(stroke
				(width 0.1)
				(type default)
			)
			(layer "F.Fab")
		)
		(fp_line
			(start -0.12065 0.3048)
			(end -0.67945 0.3048)
			(stroke
				(width 0.1)
				(type default)
			)
			(layer "F.Fab")
		)
		(fp_line
			(start 0.120396 0.3048)
			(end 0.120396 0.2794)
			(stroke
				(width 0.1)
				(type default)
			)
			(layer "F.Fab")
		)
		(fp_line
			(start 0.67945 0.3048)
			(end 0.120396 0.3048)
			(stroke
				(width 0.1)
				(type default)
			)
			(layer "F.Fab")
		)
		(fp_line
			(start -0.12065 0.2794)
			(end -0.12065 0.3048)
			(stroke
				(width 0.1)
				(type default)
			)
			(layer "F.Fab")
		)
		(fp_line
			(start 0.120396 0.2794)
			(end -0.12065 0.2794)
			(stroke
				(width 0.1)
				(type default)
			)
			(layer "F.Fab")
		)
		(fp_line
			(start -0.12065 -0.2794)
			(end 0.12065 -0.2794)
			(stroke
				(width 0.1)
				(type default)
			)
			(layer "F.Fab")
		)
		(fp_line
			(start 0.12065 -0.2794)
			(end 0.12065 -0.3048)
			(stroke
				(width 0.1)
				(type default)
			)
			(layer "F.Fab")
		)
		(fp_line
			(start 0.12065 -0.3048)
			(end 0.67945 -0.3048)
			(stroke
				(width 0.1)
				(type default)
			)
			(layer "F.Fab")
		)
		(fp_line
			(start 0.67945 -0.3048)
			(end 0.67945 0.3048)
			(stroke
				(width 0.1)
				(type default)
			)
			(layer "F.Fab")
		)
		(fp_line
			(start -0.67945 -0.305054)
			(end -0.12065 -0.305054)
			(stroke
				(width 0.1)
				(type default)
			)
			(layer "F.Fab")
		)
		(fp_line
			(start -0.12065 -0.305054)
			(end -0.12065 -0.2794)
			(stroke
				(width 0.1)
				(type default)
			)
			(layer "F.Fab")
		)
		(pad "1" smd circle
			(at -0.40005 0 270)
			(size 0 0)
			(layers "F.Cu" "F.Mask" "F.Paste")
			(net "V_VGAHS_R")
		)
		(pad "2" smd circle
			(at 0.40005 0 270)
			(size 0 0)
			(layers "F.Cu" "F.Mask" "F.Paste")
			(net "V_VGAHS")
		)
	)
	(footprint ""
		(layer "F.Cu")
		(at 114.554 112.776 -90)
		(property "Reference" "X24"
			(at -1.81483 3.0353 0)
			(unlocked yes)
			(layer "F.SilkS")
			(effects
				(font
					(size 0.7874 0.5842)
					(thickness 0.1524)
				)
				(justify left)
			)
		)
		(property "Value" ""
			(at 0 0 270)
			(layer "F.Fab")
			(effects
				(font
					(size 1.27 1.27)
				)
			)
		)
		(property "Device Type" "TP_TDR_4P_FTS_TH-TP_TDR_4P_DIPA"
			(at 1.30175 1.27 0)
			(unlocked yes)
			(layer "F.Fab")
			(hide yes)
			(effects
				(font
					(size 0.635 0.4064)
					(thickness 0.1524)
				)
			)
		)
		(property "User Part Number" "N_A"
			(at 1.30175 1.27 0)
			(unlocked yes)
			(layer "Cmts.User")
			(hide yes)
			(effects
				(font
					(size 0.635 0.4064)
					(thickness 0.1524)
				)
			)
		)
		(duplicate_pad_numbers_are_jumpers no)
		(fp_line
			(start 0 3.81)
			(end 2.54 3.81)
			(stroke
				(width 0.1524)
				(type default)
			)
			(layer "F.SilkS")
		)
		(fp_line
			(start 2.54 3.81)
			(end 2.54 3.6703)
			(stroke
				(width 0.1524)
				(type default)
			)
			(layer "F.SilkS")
		)
		(fp_line
			(start 0 3.175)
			(end 0 3.81)
			(stroke
				(width 0.1524)
				(type default)
			)
			(layer "F.SilkS")
		)
		(fp_line
			(start 2.54 1.4097)
			(end 2.54 1.1303)
			(stroke
				(width 0.1524)
				(type default)
			)
			(layer "F.SilkS")
		)
		(fp_line
			(start 0 0.635)
			(end 0 1.905)
			(stroke
				(width 0.1524)
				(type default)
			)
			(layer "F.SilkS")
		)
		(fp_line
			(start 2.54 -1.1303)
			(end 2.54 -1.27)
			(stroke
				(width 0.1524)
				(type default)
			)
			(layer "F.SilkS")
		)
		(fp_line
			(start 0 -1.27)
			(end 0 -0.635)
			(stroke
				(width 0.1524)
				(type default)
			)
			(layer "F.SilkS")
		)
		(fp_line
			(start 2.54 -1.27)
			(end 0 -1.27)
			(stroke
				(width 0.1524)
				(type default)
			)
			(layer "F.SilkS")
		)
		(fp_poly
			(pts
				(xy -0.761746 0) (xy -2.285746 -0.762) (xy -2.285746 0.762)
			)
			(stroke
				(width 0)
				(type default)
			)
			(fill yes)
			(layer "F.SilkS")
		)
		(fp_line
			(start 0 3.81)
			(end 2.54 3.81)
			(stroke
				(width 0.1)
				(type default)
			)
			(layer "F.Fab")
		)
		(fp_line
			(start 2.54 3.81)
			(end 2.54 -1.27)
			(stroke
				(width 0.1)
				(type default)
			)
			(layer "F.Fab")
		)
		(fp_line
			(start 0 -1.27)
			(end 0 3.81)
			(stroke
				(width 0.1)
				(type default)
			)
			(layer "F.Fab")
		)
		(fp_line
			(start 2.54 -1.27)
			(end 0 -1.27)
			(stroke
				(width 0.1)
				(type default)
			)
			(layer "F.Fab")
		)
		(fp_poly
			(pts
				(xy -0.761746 0) (xy -2.285746 -0.762) (xy -2.285746 0.762)
			)
			(stroke
				(width 0)
				(type default)
			)
			(fill yes)
			(layer "F.Fab")
		)
		(pad "1" thru_hole circle
			(at 0 0 270)
			(size 1.0033 1.0033)
			(drill 0.249936)
			(layers "*.Cu" "*.Mask")
			(remove_unused_layers no)
			(net "TDR_DIFF_100_BOT_DN")
			(clearance 0.10795)
			(thermal_gap 0.10795)
			(padstack
				(mode front_inner_back)
				(layer "Inner"
					(shape circle)
					(size 0.8001 0.8001)
					(clearance 0.1524)
				)
				(layer "B.Cu"
					(shape circle)
					(size 1.0033 1.0033)
					(clearance 0.10795)
				)
			)
		)
		(pad "2" thru_hole circle
			(at 2.54 0 270)
			(size 1.9939 1.9939)
			(drill 0.249936)
			(layers "*.Cu" "*.Mask")
			(remove_unused_layers no)
			(net "GND_P1")
			(clearance 0.10795)
			(thermal_gap 0.10795)
			(padstack
				(mode front_inner_back)
				(layer "Inner"
					(shape circle)
					(size 0.8001 0.8001)
					(clearance 0.1524)
				)
				(layer "B.Cu"
					(shape circle)
					(size 1.9939 1.9939)
					(clearance 0.10795)
				)
			)
		)
		(pad "3" thru_hole circle
			(at 2.54 2.54 270)
			(size 1.9939 1.9939)
			(drill 0.249936)
			(layers "*.Cu" "*.Mask")
			(remove_unused_layers no)
			(net "GND_P1")
			(clearance 0.10795)
			(thermal_gap 0.10795)
			(padstack
				(mode front_inner_back)
				(layer "Inner"
					(shape circle)
					(size 0.8001 0.8001)
					(clearance 0.1524)
				)
				(layer "B.Cu"
					(shape circle)
					(size 1.9939 1.9939)
					(clearance 0.10795)
				)
			)
		)
		(pad "4" thru_hole circle
			(at 0 2.54 270)
			(size 1.0033 1.0033)
			(drill 0.249936)
			(layers "*.Cu" "*.Mask")
			(remove_unused_layers no)
			(net "TDR_DIFF_100_BOT_DP")
			(clearance 0.10795)
			(thermal_gap 0.10795)
			(padstack
				(mode front_inner_back)
				(layer "Inner"
					(shape circle)
					(size 0.8001 0.8001)
					(clearance 0.1524)
				)
				(layer "B.Cu"
					(shape circle)
					(size 1.0033 1.0033)
					(clearance 0.10795)
				)
			)
		)
	)
	(footprint ""
		(layer "F.Cu")
		(at 64.9732 -25.0444 180)
		(property "Reference" "R512"
			(at 0 0 180)
			(layer "F.SilkS")
			(hide yes)
			(effects
				(font
					(size 1.27 1.27)
				)
			)
		)
		(property "Value" ""
			(at 0 0 180)
			(layer "F.Fab")
			(effects
				(font
					(size 1.27 1.27)
				)
			)
		)
		(duplicate_pad_numbers_are_jumpers no)
		(fp_line
			(start 0.7874 0.4064)
			(end -0.7874 0.4064)
			(stroke
				(width 0.1524)
				(type default)
			)
			(layer "F.SilkS")
		)
		(fp_line
			(start 0.7874 -0.4064)
			(end 0.7874 0.4064)
			(stroke
				(width 0.1524)
				(type default)
			)
			(layer "F.SilkS")
		)
		(fp_line
			(start -0.7874 0.4064)
			(end -0.7874 -0.4064)
			(stroke
				(width 0.1524)
				(type default)
			)
			(layer "F.SilkS")
		)
		(fp_line
			(start -0.7874 -0.4064)
			(end 0.7874 -0.4064)
			(stroke
				(width 0.1524)
				(type default)
			)
			(layer "F.SilkS")
		)
		(fp_line
			(start 0.67945 0.3048)
			(end 0.120396 0.3048)
			(stroke
				(width 0.1)
				(type default)
			)
			(layer "F.Fab")
		)
		(fp_line
			(start 0.67945 -0.3048)
			(end 0.67945 0.3048)
			(stroke
				(width 0.1)
				(type default)
			)
			(layer "F.Fab")
		)
		(fp_line
			(start 0.12065 -0.2794)
			(end 0.12065 -0.3048)
			(stroke
				(width 0.1)
				(type default)
			)
			(layer "F.Fab")
		)
		(fp_line
			(start 0.12065 -0.3048)
			(end 0.67945 -0.3048)
			(stroke
				(width 0.1)
				(type default)
			)
			(layer "F.Fab")
		)
		(fp_line
			(start 0.120396 0.3048)
			(end 0.120396 0.2794)
			(stroke
				(width 0.1)
				(type default)
			)
			(layer "F.Fab")
		)
		(fp_line
			(start 0.120396 0.2794)
			(end -0.12065 0.2794)
			(stroke
				(width 0.1)
				(type default)
			)
			(layer "F.Fab")
		)
		(fp_line
			(start -0.12065 0.3048)
			(end -0.67945 0.3048)
			(stroke
				(width 0.1)
				(type default)
			)
			(layer "F.Fab")
		)
		(fp_line
			(start -0.12065 0.2794)
			(end -0.12065 0.3048)
			(stroke
				(width 0.1)
				(type default)
			)
			(layer "F.Fab")
		)
		(fp_line
			(start -0.12065 -0.2794)
			(end 0.12065 -0.2794)
			(stroke
				(width 0.1)
				(type default)
			)
			(layer "F.Fab")
		)
		(fp_line
			(start -0.12065 -0.305054)
			(end -0.12065 -0.2794)
			(stroke
				(width 0.1)
				(type default)
			)
			(layer "F.Fab")
		)
		(fp_line
			(start -0.67945 0.3048)
			(end -0.67945 -0.305054)
			(stroke
				(width 0.1)
				(type default)
			)
			(layer "F.Fab")
		)
		(fp_line
			(start -0.67945 -0.305054)
			(end -0.12065 -0.305054)
			(stroke
				(width 0.1)
				(type default)
			)
			(layer "F.Fab")
		)
		(pad "1" smd circle
			(at -0.40005 0 180)
			(size 0 0)
			(layers "F.Cu" "F.Mask" "F.Paste")
			(net "JTAG_SCM_TDI")
		)
		(pad "2" smd circle
			(at 0.40005 0 180)
			(size 0 0)
			(layers "F.Cu" "F.Mask" "F.Paste")
			(net "JTAG_SCM_PLD_TDI")
		)
	)
)
